# S9S_MB_2U (Grand Teton) — schematic netlist excerpt (pin names and nets, part order shuffled) for the footprints in the layout excerpt that follows; sources: Cadence DE-HDL packaged netlist, KiCad conversion of 03242023_DA0F0TMBIJ0_F0T_Motherboard_J_brd_V01_OCP.brd

U217  74LVC1G126SE7  74LVC1G126SE-7 IC  pkg SOT353_0-65_2X1-25  page 161
  OE  = PU_OCP_V3_2_WAKE_OE
  A  = IRQ_LVC3_OCP_V3_2_WAKE_N
  GND  = GND
  Y  = OCP_V3_2_WAKE_BUFF_N
  VCC  = P3V3_AUX

R3635  Q_RES  0.01 1% CHIP  pkg 2512LF  page 172 : A = P12V_SCM ; B = P12V_SCM_R
R3511  Q_RES  54.9K 1% CHIP  pkg 0402LF  page 148 : A = GPU_FPGA_READY ; B = GND

(kicad_pcb
	(version 20260206)
	(generator "pcbnew")
	(generator_version "10.0")
	(general
		(thickness 1.6)
		(legacy_teardrops no)
	)
	(paper "A4")
	(title_block
		(title "03242023_DA0F0TMBIJ0_F0T_Motherboard_J_brd_V01_OCP.brd")
		(comment 1 "Grand Teton / footprints 2065-2067 of 6105")
	)
	(layers
		(0 "F.Cu" signal "TOP")
		(4 "In1.Cu" signal "GND")
		(6 "In2.Cu" signal "IN1")
		(8 "In3.Cu" signal "GND1")
		(10 "In4.Cu" signal "IN2")
		(12 "In5.Cu" signal "GND2")
		(14 "In6.Cu" signal "IN3")
		(16 "In7.Cu" signal "GND3")
		(18 "In8.Cu" signal "VCC")
		(20 "In9.Cu" signal "VCC1")
		(22 "In10.Cu" signal "GND4")
		(24 "In11.Cu" signal "IN4")
		(26 "In12.Cu" signal "GND5")
		(28 "In13.Cu" signal "IN5")
		(30 "In14.Cu" signal "GND6")
		(32 "In15.Cu" signal "IN6")
		(34 "In16.Cu" signal "GND7")
		(2 "B.Cu" signal "BOTTOM")
		(9 "F.Adhes" user "F.Adhesive")
		(11 "B.Adhes" user "B.Adhesive")
		(13 "F.Paste" user "Package Geometry/Pastemask Top")
		(15 "B.Paste" user "Package Geometry/Pastemask Bottom")
		(5 "F.SilkS" user "Ref Des/Silkscreen Top")
		(7 "B.SilkS" user "Ref Des/Silkscreen Bottom")
		(1 "F.Mask" user "Board Geometry/Soldermask Top")
		(3 "B.Mask" user "Board Geometry/Soldermask Bottom")
		(17 "Dwgs.User" user "User.Drawings")
		(19 "Cmts.User" user "User.Comments")
		(21 "Eco1.User" user "User.Eco1")
		(23 "Eco2.User" user "User.Eco2")
		(25 "Edge.Cuts" user "Board Geometry/Outline")
		(27 "Margin" user)
		(31 "F.CrtYd" user "Package Geometry/Place Bound Top")
		(29 "B.CrtYd" user "Package Geometry/Place Bound Bottom")
		(35 "F.Fab" user "Ref Des/Assembly Top")
		(33 "B.Fab" user "Ref Des/Assembly Bottom")
	)
	(footprint ""
		(layer "F.Cu")
		(at 24.050752 -403.822408 180)
		(property "Reference" "R3511"
			(at 0 0 180)
			(layer "F.SilkS")
			(hide yes)
			(effects
				(font
					(size 1.27 1.27)
				)
			)
		)
		(property "Value" ""
			(at 0 0 180)
			(layer "F.Fab")
			(effects
				(font
					(size 1.27 1.27)
				)
			)
		)
		(duplicate_pad_numbers_are_jumpers no)
		(fp_line
			(start 0.7874 0.4064)
			(end -0.7874 0.4064)
			(stroke
				(width 0.1524)
				(type default)
			)
			(layer "F.SilkS")
		)
		(fp_line
			(start 0.7874 -0.4064)
			(end 0.7874 0.4064)
			(stroke
				(width 0.1524)
				(type default)
			)
			(layer "F.SilkS")
		)
		(fp_line
			(start -0.7874 0.4064)
			(end -0.7874 -0.4064)
			(stroke
				(width 0.1524)
				(type default)
			)
			(layer "F.SilkS")
		)
		(fp_line
			(start -0.7874 -0.4064)
			(end 0.7874 -0.4064)
			(stroke
				(width 0.1524)
				(type default)
			)
			(layer "F.SilkS")
		)
		(fp_line
			(start 0.67945 0.3048)
			(end 0.120396 0.3048)
			(stroke
				(width 0.1)
				(type default)
			)
			(layer "F.Fab")
		)
		(fp_line
			(start 0.67945 -0.3048)
			(end 0.67945 0.3048)
			(stroke
				(width 0.1)
				(type default)
			)
			(layer "F.Fab")
		)
		(fp_line
			(start 0.12065 -0.2794)
			(end 0.12065 -0.3048)
			(stroke
				(width 0.1)
				(type default)
			)
			(layer "F.Fab")
		)
		(fp_line
			(start 0.12065 -0.3048)
			(end 0.67945 -0.3048)
			(stroke
				(width 0.1)
				(type default)
			)
			(layer "F.Fab")
		)
		(fp_line
			(start 0.120396 0.3048)
			(end 0.120396 0.2794)
			(stroke
				(width 0.1)
				(type default)
			)
			(layer "F.Fab")
		)
		(fp_line
			(start 0.120396 0.2794)
			(end -0.12065 0.2794)
			(stroke
				(width 0.1)
				(type default)
			)
			(layer "F.Fab")
		)
		(fp_line
			(start -0.12065 0.3048)
			(end -0.67945 0.3048)
			(stroke
				(width 0.1)
				(type default)
			)
			(layer "F.Fab")
		)
		(fp_line
			(start -0.12065 0.2794)
			(end -0.12065 0.3048)
			(stroke
				(width 0.1)
				(type default)
			)
			(layer "F.Fab")
		)
		(fp_line
			(start -0.12065 -0.2794)
			(end 0.12065 -0.2794)
			(stroke
				(width 0.1)
				(type default)
			)
			(layer "F.Fab")
		)
		(fp_line
			(start -0.12065 -0.305054)
			(end -0.12065 -0.2794)
			(stroke
				(width 0.1)
				(type default)
			)
			(layer "F.Fab")
		)
		(fp_line
			(start -0.67945 0.3048)
			(end -0.67945 -0.305054)
			(stroke
				(width 0.1)
				(type default)
			)
			(layer "F.Fab")
		)
		(fp_line
			(start -0.67945 -0.305054)
			(end -0.12065 -0.305054)
			(stroke
				(width 0.1)
				(type default)
			)
			(layer "F.Fab")
		)
		(pad "1" smd circle
			(at -0.40005 0 180)
			(size 0 0)
			(layers "F.Cu" "F.Mask" "F.Paste")
			(net "GPU_FPGA_READY")
		)
		(pad "2" smd circle
			(at 0.40005 0 180)
			(size 0 0)
			(layers "F.Cu" "F.Mask" "F.Paste")
			(net "GND")
		)
	)
	(footprint ""
		(layer "F.Cu")
		(at 278.414734 -19.279108 180)
		(property "Reference" "U217"
			(at 1.229868 1.844548 0)
			(unlocked yes)
			(layer "F.SilkS")
			(effects
				(font
					(size 0.7874 0.5842)
					(thickness 0.1524)
				)
				(justify left)
			)
		)
		(property "Value" ""
			(at 0 0 180)
			(layer "F.Fab")
			(effects
				(font
					(size 1.27 1.27)
				)
			)
		)
		(duplicate_pad_numbers_are_jumpers no)
		(fp_line
			(start 1.400048 1.100074)
			(end -1.400048 1.100074)
			(stroke
				(width 0.1524)
				(type default)
			)
			(layer "F.SilkS")
		)
		(fp_line
			(start 1.400048 -1.100074)
			(end 1.400048 1.100074)
			(stroke
				(width 0.1524)
				(type default)
			)
			(layer "F.SilkS")
		)
		(fp_line
			(start 1.400048 -1.100074)
			(end -1.400048 -1.100074)
			(stroke
				(width 0.1524)
				(type default)
			)
			(layer "F.SilkS")
		)
		(fp_line
			(start -1.400048 1.100074)
			(end -1.400048 -1.100074)
			(stroke
				(width 0.1524)
				(type default)
			)
			(layer "F.SilkS")
		)
		(fp_poly
			(pts
				(xy -1.02362 -1.291082) (xy -1.53162 -2.307082) (xy -0.51562 -2.307082)
			)
			(stroke
				(width 0)
				(type default)
			)
			(fill yes)
			(layer "F.SilkS")
		)
		(fp_line
			(start 0.674878 1.100074)
			(end -0.674878 1.100074)
			(stroke
				(width 0.1)
				(type default)
			)
			(layer "F.Fab")
		)
		(fp_line
			(start 0.674878 -1.100074)
			(end 0.674878 1.100074)
			(stroke
				(width 0.1)
				(type default)
			)
			(layer "F.Fab")
		)
		(fp_line
			(start -0.674878 1.100074)
			(end -0.674878 -1.100074)
			(stroke
				(width 0.1)
				(type default)
			)
			(layer "F.Fab")
		)
		(fp_line
			(start -0.674878 -1.100074)
			(end 0.674878 -1.100074)
			(stroke
				(width 0.1)
				(type default)
			)
			(layer "F.Fab")
		)
		(fp_poly
			(pts
				(xy -1.590548 -0.649986) (xy -2.606548 -1.157986) (xy -2.606548 -0.141986)
			)
			(stroke
				(width 0)
				(type default)
			)
			(fill yes)
			(layer "F.Fab")
		)
		(pad "1" smd rect
			(at -0.94996 -0.649986 90)
			(size 0.4318 0.6096)
			(layers "F.Cu" "F.Mask" "F.Paste")
			(net "PU_OCP_V3_2_WAKE_OE")
		)
		(pad "2" smd rect
			(at -0.94996 0 90)
			(size 0.4318 0.6096)
			(layers "F.Cu" "F.Mask" "F.Paste")
			(net "IRQ_LVC3_OCP_V3_2_WAKE_N")
		)
		(pad "3" smd rect
			(at -0.94996 0.649986 90)
			(size 0.4318 0.6096)
			(layers "F.Cu" "F.Mask" "F.Paste")
			(net "GND")
		)
		(pad "4" smd rect
			(at 0.94996 0.649986 90)
			(size 0.4318 0.6096)
			(layers "F.Cu" "F.Mask" "F.Paste")
			(net "OCP_V3_2_WAKE_BUFF_N")
		)
		(pad "5" smd rect
			(at 0.94996 -0.649986 90)
			(size 0.4318 0.6096)
			(layers "F.Cu" "F.Mask" "F.Paste")
			(net "P3V3_AUX")
		)
	)
	(footprint ""
		(layer "F.Cu")
		(at 201.047604 -35.025838 90)
		(property "Reference" "R3635"
			(at 0 0 90)
			(layer "F.SilkS")
			(hide yes)
			(effects
				(font
					(size 1.27 1.27)
				)
			)
		)
		(property "Value" ""
			(at 0 0 90)
			(layer "F.Fab")
			(effects
				(font
					(size 1.27 1.27)
				)
			)
		)
		(duplicate_pad_numbers_are_jumpers no)
		(fp_line
			(start 4.0386 -1.7526)
			(end 4.0386 1.7526)
			(stroke
				(width 0.1524)
				(type default)
			)
			(layer "F.SilkS")
		)
		(fp_line
			(start -4.0386 -1.7526)
			(end 4.0386 -1.7526)
			(stroke
				(width 0.1524)
				(type default)
			)
			(layer "F.SilkS")
		)
		(fp_line
			(start 4.0386 1.7526)
			(end -4.0386 1.7526)
			(stroke
				(width 0.1524)
				(type default)
			)
			(layer "F.SilkS")
		)
		(fp_line
			(start -4.0386 1.7526)
			(end -4.0386 -1.7526)
			(stroke
				(width 0.1524)
				(type default)
			)
			(layer "F.SilkS")
		)
		(fp_line
			(start 4.0386 -1.7526)
			(end 4.0386 1.7526)
			(stroke
				(width 0.1)
				(type default)
			)
			(layer "F.Fab")
		)
		(fp_line
			(start -4.0386 -1.7526)
			(end 4.0386 -1.7526)
			(stroke
				(width 0.1)
				(type default)
			)
			(layer "F.Fab")
		)
		(fp_line
			(start 4.0386 1.7526)
			(end -4.0386 1.7526)
			(stroke
				(width 0.1)
				(type default)
			)
			(layer "F.Fab")
		)
		(fp_line
			(start -4.0386 1.7526)
			(end -4.0386 -1.7526)
			(stroke
				(width 0.1)
				(type default)
			)
			(layer "F.Fab")
		)
		(pad "1" smd rect
			(at -3.1115 0 90)
			(size 1.524 3.2004)
			(layers "F.Cu" "F.Mask" "F.Paste")
			(net "P12V_SCM")
		)
		(pad "2" smd rect
			(at 3.1115 0 90)
			(size 1.524 3.2004)
			(layers "F.Cu" "F.Mask" "F.Paste")
			(net "P12V_SCM_R")
		)
	)
)
